(kicad_pcb
	(version 20241229)
	(generator "pcbnew")
	(generator_version "9.0")
	(general
		(thickness 1.6296)
		(legacy_teardrops no)
	)
	(paper "A3")
	(title_block
		(title "Thunderbolt to 10GbE adapter")
		(date "2026-04-21")
		(rev "1.1.0")
		(company "Antmicro Ltd")
		(comment 1 "www.antmicro.com")
		(comment 9 "footprints 174-178 of 703")
	)
	(layers
		(0 "F.Cu" signal)
		(4 "In1.Cu" signal)
		(6 "In2.Cu" signal)
		(8 "In3.Cu" signal)
		(10 "In4.Cu" signal)
		(12 "In5.Cu" signal)
		(14 "In6.Cu" signal)
		(2 "B.Cu" signal)
		(9 "F.Adhes" user "F.Adhesive")
		(11 "B.Adhes" user "B.Adhesive")
		(13 "F.Paste" user)
		(15 "B.Paste" user)
		(5 "F.SilkS" user "F.Silkscreen")
		(7 "B.SilkS" user "B.Silkscreen")
		(1 "F.Mask" user)
		(3 "B.Mask" user)
		(17 "Dwgs.User" user "User.Drawings")
		(19 "Cmts.User" user "User.Comments")
		(21 "Eco1.User" user "User.Eco1")
		(23 "Eco2.User" user "User.Eco2")
		(25 "Edge.Cuts" user)
		(27 "Margin" user)
		(31 "F.CrtYd" user "F.Courtyard")
		(29 "B.CrtYd" user "B.Courtyard")
		(35 "F.Fab" user)
		(33 "B.Fab" user)
	)
	(footprint "antmicro-footprints:C_0805_2012Metric"
		(layer "F.Cu")
		(at 165.304999 95.174998 180)
		(descr "Capacitor SMD 0805")
		(tags "capacitor SMD 0805")
		(property "Reference" "C171"
			(at -7.695 0 180)
			(layer "F.SilkS")
			(effects
				(font
					(size 0.7 0.7)
					(thickness 0.15)
				)
			)
		)
		(property "Value" "C_100u_0805"
			(at -2.055717 1.963152 180)
			(layer "F.Fab")
			(effects
				(font
					(size 0.7 0.7)
					(thickness 0.15)
				)
				(justify left bottom)
			)
		)
		(property "Datasheet" "https://www.murata.com/products/productdetail?partno=GRM21BR60J107ME15%23"
			(at 0 0 180)
			(layer "F.Fab")
			(hide yes)
			(effects
				(font
					(size 1.27 1.27)
					(thickness 0.15)
				)
			)
		)
		(property "Description" "SMD Multilayer Ceramic Capacitor, 100 µF, 6.3 V, 0805 [2012 Metric], ± 20%, X5R, GRM Series"
			(at 0 0 180)
			(layer "F.Fab")
			(hide yes)
			(effects
				(font
					(size 1.27 1.27)
					(thickness 0.15)
				)
			)
		)
		(property "MPN" "GRM21BR60J107ME15L"
			(at 0 0 180)
			(unlocked yes)
			(layer "F.Fab")
			(hide yes)
			(effects
				(font
					(size 1 1)
					(thickness 0.15)
				)
			)
		)
		(property "Manufacturer" "Murata"
			(at 0 0 180)
			(unlocked yes)
			(layer "F.Fab")
			(hide yes)
			(effects
				(font
					(size 1 1)
					(thickness 0.15)
				)
			)
		)
		(property "License" "Apache-2.0"
			(at 0 0 180)
			(unlocked yes)
			(layer "F.Fab")
			(hide yes)
			(effects
				(font
					(size 1 1)
					(thickness 0.15)
				)
			)
		)
		(property "Author" "Antmicro"
			(at 0 0 180)
			(unlocked yes)
			(layer "F.Fab")
			(hide yes)
			(effects
				(font
					(size 1 1)
					(thickness 0.15)
				)
			)
		)
		(property "Val" "100u"
			(at 0 0 180)
			(unlocked yes)
			(layer "F.Fab")
			(hide yes)
			(effects
				(font
					(size 1 1)
					(thickness 0.15)
				)
			)
		)
		(property "Voltage" ""
			(at 0 0 180)
			(unlocked yes)
			(layer "F.Fab")
			(hide yes)
			(effects
				(font
					(size 1 1)
					(thickness 0.15)
				)
			)
		)
		(property "Dielectric" ""
			(at 0 0 180)
			(unlocked yes)
			(layer "F.Fab")
			(hide yes)
			(effects
				(font
					(size 1 1)
					(thickness 0.15)
				)
			)
		)
		(property "Public" "False"
			(at 0 0 180)
			(unlocked yes)
			(layer "F.Fab")
			(hide yes)
			(effects
				(font
					(size 1 1)
					(thickness 0.15)
				)
			)
		)
		(sheetname "/X710-AT2 power/")
		(sheetfile "x710-at2-power.kicad_sch")
		(attr smd)
		(fp_line
			(start -0.3 0.7)
			(end 0.3 0.7)
			(stroke
				(width 0.15)
				(type solid)
			)
			(layer "F.SilkS")
		)
		(fp_line
			(start -0.3 -0.7)
			(end 0.3 -0.7)
			(stroke
				(width 0.15)
				(type solid)
			)
			(layer "F.SilkS")
		)
		(fp_rect
			(start 1.95 -0.9)
			(end -1.95 0.9)
			(stroke
				(width 0.05)
				(type default)
			)
			(fill no)
			(layer "F.CrtYd")
		)
		(fp_rect
			(start -0.95 -0.675)
			(end 0.95 0.675)
			(stroke
				(width 0.15)
				(type solid)
			)
			(fill no)
			(layer "F.Fab")
		)
		(fp_text user "License: Apache-2.0"
			(at -1.9 4.947 180)
			(layer "F.Fab")
			(effects
				(font
					(size 0.7 0.7)
					(thickness 0.15)
				)
				(justify left bottom)
			)
		)
		(fp_text user "Author: Antmicro"
			(at -1.9 5.947 180)
			(layer "F.Fab")
			(effects
				(font
					(size 0.7 0.7)
					(thickness 0.15)
				)
				(justify left bottom)
			)
		)
		(fp_text user "${REFERENCE}"
			(at -1.9 3.947 180)
			(layer "F.Fab")
			(effects
				(font
					(size 0.7 0.7)
					(thickness 0.15)
				)
				(justify left bottom)
			)
		)
		(pad "1" smd roundrect
			(at -1.1 0 180)
			(size 1.2 1.3)
			(layers "F.Cu" "F.Mask" "F.Paste")
			(roundrect_rratio 0.25)
			(net 23 "GND")
			(pintype "passive")
		)
		(pad "2" smd roundrect
			(at 1.1 0 180)
			(size 1.2 1.3)
			(layers "F.Cu" "F.Mask" "F.Paste")
			(roundrect_rratio 0.25)
			(net 14 "P1_AVDDL")
			(pintype "passive")
		)
	)
	(footprint "antmicro-footprints:R_0402_1005Metric"
		(layer "F.Cu")
		(at 164 77.4)
		(descr "Resistor SMD 0402")
		(tags "resistor SMD 0402")
		(property "Reference" "R207"
			(at -1 6.4 0)
			(layer "F.SilkS")
			(effects
				(font
					(size 0.7 0.7)
					(thickness 0.15)
				)
				(justify left bottom)
			)
		)
		(property "Value" "R_1k_0402"
			(at -1.011843 1.772047 0)
			(layer "F.Fab")
			(effects
				(font
					(size 0.7 0.7)
					(thickness 0.15)
				)
				(justify left bottom)
			)
		)
		(property "Datasheet" "https://www.bourns.com/docs/product-datasheets/cr.pdf"
			(at 0 0 0)
			(layer "F.Fab")
			(hide yes)
			(effects
				(font
					(size 1.27 1.27)
					(thickness 0.15)
				)
			)
		)
		(property "Description" "SMD Chip Resistor, 1 kohm, ± 1%, 63 mW, 0402 [1005 Metric], Thick Film, General Purpose"
			(at 0 0 0)
			(layer "F.Fab")
			(hide yes)
			(effects
				(font
					(size 1.27 1.27)
					(thickness 0.15)
				)
			)
		)
		(property "MPN" "CR0402-FX-1001GLF"
			(at 0 0 0)
			(unlocked yes)
			(layer "F.Fab")
			(hide yes)
			(effects
				(font
					(size 1 1)
					(thickness 0.15)
				)
			)
		)
		(property "Manufacturer" "Bourns"
			(at 0 0 0)
			(unlocked yes)
			(layer "F.Fab")
			(hide yes)
			(effects
				(font
					(size 1 1)
					(thickness 0.15)
				)
			)
		)
		(property "License" "Apache-2.0"
			(at 0 0 0)
			(unlocked yes)
			(layer "F.Fab")
			(hide yes)
			(effects
				(font
					(size 1 1)
					(thickness 0.15)
				)
			)
		)
		(property "Author" "Antmicro"
			(at 0 0 0)
			(unlocked yes)
			(layer "F.Fab")
			(hide yes)
			(effects
				(font
					(size 1 1)
					(thickness 0.15)
				)
			)
		)
		(property "Val" "1k"
			(at 0 0 0)
			(unlocked yes)
			(layer "F.Fab")
			(hide yes)
			(effects
				(font
					(size 1 1)
					(thickness 0.15)
				)
			)
		)
		(property "Tolerance" "1%"
			(at 0 0 0)
			(unlocked yes)
			(layer "F.Fab")
			(hide yes)
			(effects
				(font
					(size 1 1)
					(thickness 0.15)
				)
			)
		)
		(sheetname "/X710-AT2 10GbE/")
		(sheetfile "x710-at2-10gbe.kicad_sch")
		(attr smd dnp)
		(fp_rect
			(start -0.925 -0.47)
			(end 0.925 0.47)
			(stroke
				(width 0.05)
				(type default)
			)
			(fill no)
			(layer "F.CrtYd")
		)
		(fp_rect
			(start -0.5 -0.25)
			(end 0.5 0.25)
			(stroke
				(width 0.15)
				(type solid)
			)
			(fill no)
			(layer "F.Fab")
		)
		(fp_text user "License: Apache-2.0"
			(at -0.95 5.169 0)
			(layer "F.Fab")
			(effects
				(font
					(size 0.7 0.7)
					(thickness 0.15)
				)
				(justify left bottom)
			)
		)
		(fp_text user "Author: Antmicro"
			(at -0.95 4.169 0)
			(layer "F.Fab")
			(effects
				(font
					(size 0.7 0.7)
					(thickness 0.15)
				)
				(justify left bottom)
			)
		)
		(fp_text user "${REFERENCE}"
			(at -0.95 3.168 0)
			(layer "F.Fab")
			(effects
				(font
					(size 0.7 0.7)
					(thickness 0.15)
				)
				(justify left bottom)
			)
		)
		(pad "1" smd roundrect
			(at -0.48 0)
			(size 0.59 0.64)
			(layers "F.Cu" "F.Mask" "F.Paste")
			(roundrect_rratio 0.25)
			(net 131 "/X710-AT2 10GbE/TPIN_5")
			(pintype "passive")
		)
		(pad "2" smd roundrect
			(at 0.48 0)
			(size 0.59 0.64)
			(layers "F.Cu" "F.Mask" "F.Paste")
			(roundrect_rratio 0.25)
			(net 18 "+1V88")
			(pintype "passive")
		)
	)
	(footprint "antmicro-footprints:C_0402_1005Metric"
		(layer "F.Cu")
		(at 172.6 74 90)
		(descr "Capacitor SMD 0402")
		(tags "capacitor SMD 0402")
		(property "Reference" "C285"
			(at -1.2 3.6 90)
			(layer "F.SilkS")
			(effects
				(font
					(size 0.7 0.7)
					(thickness 0.15)
				)
				(justify left bottom)
			)
		)
		(property "Value" "C_10p_25V_0402"
			(at -1.022927 2.155213 90)
			(layer "F.Fab")
			(effects
				(font
					(size 0.7 0.7)
					(thickness 0.15)
				)
				(justify left bottom)
			)
		)
		(property "Datasheet" "https://spicat.kyocera-avx.com/product/mlcc/chartview/04023A100FAT2A/"
			(at 0 0 90)
			(layer "F.Fab")
			(hide yes)
			(effects
				(font
					(size 1.27 1.27)
					(thickness 0.15)
				)
			)
		)
		(property "Description" "Multilayer Ceramic Capacitors MLCC - SMD/SMT 25V 10pF C0G 0402 1%"
			(at 0 0 90)
			(layer "F.Fab")
			(hide yes)
			(effects
				(font
					(size 1.27 1.27)
					(thickness 0.15)
				)
			)
		)
		(property "MPN" "04023A100FAT2A"
			(at 0 0 90)
			(unlocked yes)
			(layer "F.Fab")
			(hide yes)
			(effects
				(font
					(size 1 1)
					(thickness 0.15)
				)
			)
		)
		(property "Manufacturer" "KYOCERA AVX"
			(at 0 0 90)
			(unlocked yes)
			(layer "F.Fab")
			(hide yes)
			(effects
				(font
					(size 1 1)
					(thickness 0.15)
				)
			)
		)
		(property "License" "Apache-2.0"
			(at 0 0 90)
			(unlocked yes)
			(layer "F.Fab")
			(hide yes)
			(effects
				(font
					(size 1 1)
					(thickness 0.15)
				)
			)
		)
		(property "Author" "Antmicro"
			(at 0 0 90)
			(unlocked yes)
			(layer "F.Fab")
			(hide yes)
			(effects
				(font
					(size 1 1)
					(thickness 0.15)
				)
			)
		)
		(property "Val" "10p"
			(at 0 0 90)
			(unlocked yes)
			(layer "F.Fab")
			(hide yes)
			(effects
				(font
					(size 1 1)
					(thickness 0.15)
				)
			)
		)
		(property "Voltage" "25V"
			(at 0 0 90)
			(unlocked yes)
			(layer "F.Fab")
			(hide yes)
			(effects
				(font
					(size 1 1)
					(thickness 0.15)
				)
			)
		)
		(property "Dielectric" "C0G"
			(at 0 0 90)
			(unlocked yes)
			(layer "F.Fab")
			(hide yes)
			(effects
				(font
					(size 1 1)
					(thickness 0.15)
				)
			)
		)
		(sheetname "/X710-AT2 10GbE/")
		(sheetfile "x710-at2-10gbe.kicad_sch")
		(attr smd)
		(fp_rect
			(start -0.925 -0.47)
			(end 0.925 0.47)
			(stroke
				(width 0.05)
				(type default)
			)
			(fill no)
			(layer "F.CrtYd")
		)
		(fp_line
			(start 0.504 -0.25)
			(end 0.504 0.248)
			(stroke
				(width 0.15)
				(type solid)
			)
			(layer "F.Fab")
		)
		(fp_line
			(start -0.494 -0.25)
			(end 0.504 -0.25)
			(stroke
				(width 0.15)
				(type solid)
			)
			(layer "F.Fab")
		)
		(fp_line
			(start 0.504 0.248)
			(end -0.494 0.248)
			(stroke
				(width 0.15)
				(type solid)
			)
			(layer "F.Fab")
		)
		(fp_line
			(start -0.494 0.248)
			(end -0.494 -0.25)
			(stroke
				(width 0.15)
				(type solid)
			)
			(layer "F.Fab")
		)
		(fp_text user "Author: Antmicro"
			(at -0.939 3.399 90)
			(layer "F.Fab")
			(effects
				(font
					(size 0.7 0.7)
					(thickness 0.15)
				)
				(justify left bottom)
			)
		)
		(fp_text user "${REFERENCE}"
			(at -0.939 4.599 90)
			(layer "F.Fab")
			(effects
				(font
					(size 0.7 0.7)
					(thickness 0.15)
				)
				(justify left bottom)
			)
		)
		(fp_text user "License: Apache-2.0"
			(at -0.939 5.799 90)
			(layer "F.Fab")
			(effects
				(font
					(size 0.7 0.7)
					(thickness 0.15)
				)
				(justify left bottom)
			)
		)
		(pad "1" smd roundrect
			(at -0.48 0 90)
			(size 0.59 0.64)
			(layers "F.Cu" "F.Mask" "F.Paste")
			(roundrect_rratio 0.25)
			(net 23 "GND")
			(pintype "passive")
		)
		(pad "2" smd roundrect
			(at 0.48 0 90)
			(size 0.59 0.64)
			(layers "F.Cu" "F.Mask" "F.Paste")
			(roundrect_rratio 0.25)
			(net 125 "/X710-AT2 10GbE/MDIO0_I2C0.MDC")
			(pintype "passive")
		)
	)
	(footprint "antmicro-footprints:FB_0603_1608Metric"
		(layer "F.Cu")
		(at 146.355 97.375 90)
		(property "Reference" "FB4"
			(at -19.625001 23.445 90)
			(layer "F.SilkS")
			(effects
				(font
					(size 0.7 0.7)
					(thickness 0.15)
				)
			)
		)
		(property "Value" "FB_470Z_1A_Murata-BLM18PG_0603"
			(at 0 1.5 90)
			(layer "F.Fab")
			(effects
				(font
					(size 0.7 0.7)
					(thickness 0.15)
				)
				(justify left bottom)
			)
		)
		(property "Datasheet" "https://www.murata.com/en-us/products/productdata/8796738650142/ENFA0003.pdf"
			(at 0 0 90)
			(layer "F.Fab")
			(hide yes)
			(effects
				(font
					(size 1.27 1.27)
					(thickness 0.15)
				)
			)
		)
		(property "Description" "Ferrite Bead, 0603 [1608 Metric], 470 ohm, 1 A, BLM18P, 0.2 ohm, ± 25%, DC power line"
			(at 0 0 90)
			(layer "F.Fab")
			(hide yes)
			(effects
				(font
					(size 1.27 1.27)
					(thickness 0.15)
				)
			)
		)
		(property "Val" "470Z/1A"
			(at 0 0 90)
			(unlocked yes)
			(layer "F.Fab")
			(hide yes)
			(effects
				(font
					(size 1 1)
					(thickness 0.15)
				)
			)
		)
		(property "MPN" "BLM18PG471SN1D"
			(at 0 0 90)
			(unlocked yes)
			(layer "F.Fab")
			(hide yes)
			(effects
				(font
					(size 1 1)
					(thickness 0.15)
				)
			)
		)
		(property "Manufacturer" "Murata"
			(at 0 0 90)
			(unlocked yes)
			(layer "F.Fab")
			(hide yes)
			(effects
				(font
					(size 1 1)
					(thickness 0.15)
				)
			)
		)
		(property "Current" ""
			(at 0 0 90)
			(unlocked yes)
			(layer "F.Fab")
			(hide yes)
			(effects
				(font
					(size 1 1)
					(thickness 0.15)
				)
			)
		)
		(property "Author" "Antmicro"
			(at 0 0 90)
			(unlocked yes)
			(layer "F.Fab")
			(hide yes)
			(effects
				(font
					(size 1 1)
					(thickness 0.15)
				)
			)
		)
		(property "License" "Apache-2.0"
			(at 0 0 90)
			(unlocked yes)
			(layer "F.Fab")
			(hide yes)
			(effects
				(font
					(size 1 1)
					(thickness 0.15)
				)
			)
		)
		(sheetname "/X710-AT2 power/")
		(sheetfile "x710-at2-power.kicad_sch")
		(attr smd)
		(fp_line
			(start -0.15 -0.4)
			(end 0.15 -0.4)
			(stroke
				(width 0.15)
				(type solid)
			)
			(layer "F.SilkS")
		)
		(fp_line
			(start -0.15 0.4)
			(end 0.15 0.4)
			(stroke
				(width 0.15)
				(type solid)
			)
			(layer "F.SilkS")
		)
		(fp_rect
			(start -1.25 -0.65)
			(end 1.25 0.65)
			(stroke
				(width 0.05)
				(type solid)
			)
			(fill no)
			(layer "F.CrtYd")
		)
		(fp_line
			(start 0.8 -0.408)
			(end -0.803 -0.408)
			(stroke
				(width 0.15)
				(type solid)
			)
			(layer "F.Fab")
		)
		(fp_line
			(start 0.8 -0.408)
			(end 0.8 0.406)
			(stroke
				(width 0.15)
				(type solid)
			)
			(layer "F.Fab")
		)
		(fp_line
			(start 0.8 0.406)
			(end -0.803 0.406)
			(stroke
				(width 0.15)
				(type solid)
			)
			(layer "F.Fab")
		)
		(fp_line
			(start -0.803 0.406)
			(end -0.803 -0.408)
			(stroke
				(width 0.15)
				(type solid)
			)
			(layer "F.Fab")
		)
		(fp_text user "License: Apache-2.0"
			(at -1.653 5.9 90)
			(layer "F.Fab")
			(effects
				(font
					(size 0.7 0.7)
					(thickness 0.15)
				)
				(justify left bottom)
			)
		)
		(fp_text user "${REFERENCE}"
			(at -1.653 4.6 90)
			(layer "F.Fab")
			(effects
				(font
					(size 0.7 0.7)
					(thickness 0.15)
				)
				(justify left bottom)
			)
		)
		(fp_text user "Author: Antmicro"
			(at -1.653 3.162 90)
			(layer "F.Fab")
			(effects
				(font
					(size 0.7 0.7)
					(thickness 0.15)
				)
				(justify left bottom)
			)
		)
		(pad "1" smd roundrect
			(at -0.7 0 90)
			(size 0.8 1)
			(layers "F.Cu" "F.Mask" "F.Paste")
			(roundrect_rratio 0.2)
			(net 18 "+1V88")
			(pintype "passive")
		)
		(pad "2" smd roundrect
			(at 0.7 0 90)
			(size 0.8 1)
			(layers "F.Cu" "F.Mask" "F.Paste")
			(roundrect_rratio 0.2)
			(net 20 "XGB_AVDDH")
			(pintype "passive")
		)
	)
	(footprint "antmicro-footprints:C_0402_1005Metric"
		(layer "F.Cu")
		(at 117.8 119 180)
		(descr "Capacitor SMD 0402")
		(tags "capacitor SMD 0402")
		(property "Reference" "C48"
			(at -0.8 -0.2 180)
			(layer "F.SilkS")
			(effects
				(font
					(size 0.7 0.7)
					(thickness 0.15)
				)
				(justify left bottom)
			)
		)
		(property "Value" "C_220n_0402"
			(at -1.022927 2.155213 180)
			(layer "F.Fab")
			(effects
				(font
					(size 0.7 0.7)
					(thickness 0.15)
				)
				(justify left bottom)
			)
		)
		(property "Datasheet" "https://www.yageo.com/en/Chart/Download/pdf/CC0402KRX5R6BB224"
			(at 0 0 180)
			(layer "F.Fab")
			(hide yes)
			(effects
				(font
					(size 1.27 1.27)
					(thickness 0.15)
				)
			)
		)
		(property "Description" "SMD Multilayer Ceramic Capacitor, 0.22 µF, 10 V, 0402 [1005 Metric], ± 10%, X5R, CC Series"
			(at 0 0 180)
			(layer "F.Fab")
			(hide yes)
			(effects
				(font
					(size 1.27 1.27)
					(thickness 0.15)
				)
			)
		)
		(property "MPN" "CC0402KRX5R6BB224"
			(at 0 0 180)
			(unlocked yes)
			(layer "F.Fab")
			(hide yes)
			(effects
				(font
					(size 1 1)
					(thickness 0.15)
				)
			)
		)
		(property "Manufacturer" "YAGEO"
			(at 0 0 180)
			(unlocked yes)
			(layer "F.Fab")
			(hide yes)
			(effects
				(font
					(size 1 1)
					(thickness 0.15)
				)
			)
		)
		(property "License" "Apache-2.0"
			(at 0 0 180)
			(unlocked yes)
			(layer "F.Fab")
			(hide yes)
			(effects
				(font
					(size 1 1)
					(thickness 0.15)
				)
			)
		)
		(property "Val" "220n"
			(at 0 0 180)
			(unlocked yes)
			(layer "F.Fab")
			(hide yes)
			(effects
				(font
					(size 1 1)
					(thickness 0.15)
				)
			)
		)
		(property "Voltage" ""
			(at 0 0 180)
			(unlocked yes)
			(layer "F.Fab")
			(hide yes)
			(effects
				(font
					(size 1 1)
					(thickness 0.15)
				)
			)
		)
		(property "Dielectric" ""
			(at 0 0 180)
			(unlocked yes)
			(layer "F.Fab")
			(hide yes)
			(effects
				(font
					(size 1 1)
					(thickness 0.15)
				)
			)
		)
		(property "Author" "Antmicro"
			(at 0 0 180)
			(unlocked yes)
			(layer "F.Fab")
			(hide yes)
			(effects
				(font
					(size 1 1)
					(thickness 0.15)
				)
			)
		)
		(sheetname "/TB Controller/")
		(sheetfile "tb.kicad_sch")
		(attr smd)
		(fp_rect
			(start -0.925 -0.47)
			(end 0.925 0.47)
			(stroke
				(width 0.05)
				(type default)
			)
			(fill no)
			(layer "F.CrtYd")
		)
		(fp_line
			(start 0.504 0.248)
			(end -0.494 0.248)
			(stroke
				(width 0.15)
				(type solid)
			)
			(layer "F.Fab")
		)
		(fp_line
			(start 0.504 -0.25)
			(end 0.504 0.248)
			(stroke
				(width 0.15)
				(type solid)
			)
			(layer "F.Fab")
		)
		(fp_line
			(start -0.494 0.248)
			(end -0.494 -0.25)
			(stroke
				(width 0.15)
				(type solid)
			)
			(layer "F.Fab")
		)
		(fp_line
			(start -0.494 -0.25)
			(end 0.504 -0.25)
			(stroke
				(width 0.15)
				(type solid)
			)
			(layer "F.Fab")
		)
		(fp_text user "Author: Antmicro"
			(at -0.939 3.399 180)
			(layer "F.Fab")
			(effects
				(font
					(size 0.7 0.7)
					(thickness 0.15)
				)
				(justify left bottom)
			)
		)
		(fp_text user "${REFERENCE}"
			(at -0.939 4.599 180)
			(layer "F.Fab")
			(effects
				(font
					(size 0.7 0.7)
					(thickness 0.15)
				)
				(justify left bottom)
			)
		)
		(fp_text user "License: Apache-2.0"
			(at -0.939 5.799 180)
			(layer "F.Fab")
			(effects
				(font
					(size 0.7 0.7)
					(thickness 0.15)
				)
				(justify left bottom)
			)
		)
		(pad "1" smd roundrect
			(at -0.48 0 180)
			(size 0.59 0.64)
			(layers "F.Cu" "F.Mask" "F.Paste")
			(roundrect_rratio 0.25)
			(net 315 "/TB Controller/TB_PCIE_TX0_N")
			(pintype "passive")
		)
		(pad "2" smd roundrect
			(at 0.48 0 180)
			(size 0.59 0.64)
			(layers "F.Cu" "F.Mask" "F.Paste")
			(roundrect_rratio 0.25)
			(net 322 "/TB Controller/PCIex4.RX0-")
			(pintype "passive")
		)
	)
)
